FILE_TYPE = CONNECTIVITY;
{Allegro Design Entry HDL 17.4-2019 S026 (4007227) 1/17/2022}
"PAGE_NUMBER" = 96;
0"NC";
1"GND\g";
2"GND\g";
3"P3V3\g";
4"M_L_CPU0_SA_CB<7:0>";
5"M_L_CPU0_SB_CB<7:0>";
6"M_L_CPU0_SA_CA<6:0>";
7"M_L_CPU0_SB_CA<6:0>";
8"M_L_CPU0_SA_DQ<31:0>";
9"M_L_CPU0_SB_DQ<31:0>";
10"M_L_CPU0_SA_DQS_DN<9:0>";
11"M_L_CPU0_SA_DQS_DP<9:0>";
12"M_L_CPU0_SB_DQS_DP<9:0>";
13"M_L_CPU0_SB_DQS_DN<9:0>";
14"M_L_CPU0_ALERT_N";
15"M_L_CPU0_RESET_N";
16"PWRGD_CHGL_CPU0";
17"M_L_CPU0_SB_DQ<17>";
18"M_L_CPU0_SB_DQ<7>";
19"M_L_CPU0_SB_DQ<9>";
20"M_L_CPU0_SB_DQ<11>";
21"M_L_CPU0_SB_CB<4>";
22"M_L_CPU0_SA_DQ<2>";
23"M_L_CPU0_SA_DQ<3>";
24"M_L_CPU0_SA_DQ<4>";
25"M_L_CPU0_SB_RSP<0>";
26"M_L_CPU0_SB_DQS_DP<9>";
27"M_L_CPU0_SB_DQS_DN<9>";
28"M_L_CPU0_SA_DQS_DP<9>";
29"M_L_CPU0_SA_DQS_DN<9>";
30"M_L_CPU0_SA_DQS_DP<8>";
31"M_L_CPU0_SA_DQS_DN<8>";
32"M_L_CPU0_SB_DQS_DN<7>";
33"M_L_CPU0_SA_DQS_DP<7>";
34"M_L_CPU0_SB_DQS_DP<6>";
35"M_L_CPU0_SB_DQS_DN<6>";
36"M_L_CPU0_SA_DQS_DN<6>";
37"M_L_CPU0_SB_DQS_DP<5>";
38"M_L_CPU0_SB_DQS_DN<5>";
39"M_L_CPU0_SA_DQS_DP<5>";
40"M_L_CPU0_SA_DQS_DN<5>";
41"M_L_CPU0_SB_DQS_DP<4>";
42"M_L_CPU0_SB_DQS_DN<4>";
43"M_L_CPU0_SA_DQS_DP<4>";
44"M_L_CPU0_SA_DQS_DN<4>";
45"M_L_CPU0_SB_DQS_DP<3>";
46"M_L_CPU0_SB_DQS_DN<3>";
47"M_L_CPU0_SA_DQS_DP<3>";
48"M_L_CPU0_SA_DQS_DN<3>";
49"M_L_CPU0_SB_DQS_DP<2>";
50"M_L_CPU0_SB_DQS_DN<2>";
51"M_L_CPU0_SA_DQS_DP<2>";
52"M_L_CPU0_SA_DQS_DN<2>";
53"M_L_CPU0_SB_DQS_DP<1>";
54"M_L_CPU0_SB_DQS_DN<1>";
55"M_L_CPU0_SA_DQS_DP<1>";
56"M_L_CPU0_SA_DQS_DN<1>";
57"M_L_CPU0_SB_DQS_DP<0>";
58"M_L_CPU0_SB_DQS_DN<0>";
59"M_L_CPU0_SA_DQS_DP<0>";
60"M_L_CPU0_SA_DQS_DN<0>";
61"M_L_CPU0_SB_DQS_DP<7>";
62"M_L_CPU0_SB_DQS_DN<8>";
63"M_L_CPU0_SB_DQS_DP<8>";
64"M_L_CPU0_SA_DQS_DP<6>";
65"M_L_CPU0_SA_DQS_DN<7>";
66"M_L_CPU0_SA_DQ<18>";
67"M_L_CPU0_SA_DQ<30>";
68"M_L_CPU0_SA_DQ<31>";
69"M_L_CPU0_SB_PAR";
70"M_L_CPU0_SA_PAR";
71"M_L_CPU0_SB_DQ<0>";
72"M_L_CPU0_SB_DQ<1>";
73"M_L_CPU0_SB_DQ<2>";
74"M_L_CPU0_SB_DQ<3>";
75"M_L_CPU0_SB_DQ<4>";
76"M_L_CPU0_SB_DQ<5>";
77"M_L_CPU0_SB_DQ<6>";
78"M_L_CPU0_SB_DQ<8>";
79"M_L_CPU0_SB_DQ<10>";
80"M_L_CPU0_SB_DQ<12>";
81"M_L_CPU0_SB_DQ<13>";
82"M_L_CPU0_SB_DQ<14>";
83"M_L_CPU0_SB_DQ<15>";
84"M_L_CPU0_SB_DQ<16>";
85"M_L_CPU0_SB_DQ<18>";
86"M_L_CPU0_SB_DQ<19>";
87"M_L_CPU0_SB_DQ<20>";
88"M_L_CPU0_SB_DQ<21>";
89"M_L_CPU0_SB_DQ<22>";
90"M_L_CPU0_SB_DQ<23>";
91"M_L_CPU0_SB_DQ<24>";
92"M_L_CPU0_SB_DQ<25>";
93"M_L_CPU0_SB_DQ<26>";
94"M_L_CPU0_SB_DQ<27>";
95"M_L_CPU0_SB_DQ<28>";
96"M_L_CPU0_SB_DQ<29>";
97"M_L_CPU0_SB_DQ<30>";
98"M_L_CPU0_SB_DQ<31>";
99"M_L_CPU0_SA_DQ<0>";
100"M_L_CPU0_SA_DQ<1>";
101"M_L_CPU0_SA_DQ<5>";
102"M_L_CPU0_SA_DQ<6>";
103"M_L_CPU0_SA_DQ<7>";
104"M_L_CPU0_SA_DQ<8>";
105"M_L_CPU0_SA_DQ<9>";
106"M_L_CPU0_SA_DQ<10>";
107"M_L_CPU0_SA_DQ<11>";
108"M_L_CPU0_SA_DQ<12>";
109"M_L_CPU0_SA_DQ<13>";
110"M_L_CPU0_SA_DQ<14>";
111"M_L_CPU0_SA_DQ<15>";
112"M_L_CPU0_SA_DQ<16>";
113"M_L_CPU0_SA_DQ<17>";
114"M_L_CPU0_SA_DQ<19>";
115"M_L_CPU0_SA_DQ<20>";
116"M_L_CPU0_SA_DQ<21>";
117"M_L_CPU0_SA_DQ<22>";
118"M_L_CPU0_SA_DQ<23>";
119"M_L_CPU0_SA_DQ<24>";
120"M_L_CPU0_SA_DQ<25>";
121"M_L_CPU0_SA_DQ<26>";
122"M_L_CPU0_SA_DQ<27>";
123"M_L_CPU0_SA_DQ<28>";
124"M_L_CPU0_SA_DQ<29>";
125"M_L_CPU0_SB_CS_N<1>";
126"M_L_CPU0_SA_CS_N<1>";
127"M_L_CPU0_SB_CS_N<0>";
128"M_L_CPU0_SA_CS_N<0>";
129"M_L_CPU0_CLK_DP<0>";
130"M_L_CPU0_CLK_DN<0>";
131"M_L_CPU0_SB_CB<0>";
132"M_L_CPU0_SB_CB<1>";
133"M_L_CPU0_SB_CB<2>";
134"M_L_CPU0_SB_CB<3>";
135"M_L_CPU0_SB_CB<5>";
136"M_L_CPU0_SB_CB<6>";
137"M_L_CPU0_SA_CB<0>";
138"M_L_CPU0_SA_CB<2>";
139"M_L_CPU0_SA_CB<3>";
140"M_L_CPU0_SA_CB<5>";
141"M_L_CPU0_SA_CB<6>";
142"M_L_CPU0_SB_CA<6>";
143"M_L_CPU0_SA_CA<6>";
144"M_L_CPU0_SB_CA<5>";
145"M_L_CPU0_SA_CA<5>";
146"M_L_CPU0_SB_CA<4>";
147"M_L_CPU0_SA_CA<4>";
148"M_L_CPU0_SB_CA<3>";
149"M_L_CPU0_SA_CA<3>";
150"M_L_CPU0_SB_CA<2>";
151"M_L_CPU0_SA_CA<2>";
152"M_L_CPU0_SB_CA<1>";
153"M_L_CPU0_SA_CA<1>";
154"M_L_CPU0_SB_CA<0>";
155"M_L_CPU0_SA_CA<0>";
156"M_L_CPU0_SB_CB<7>";
157"M_L_CPU0_SA_CB<1>";
158"M_L_CPU0_SA_CB<4>";
159"M_L_CPU0_SA_CB<7>";
160"PD_CHL_CPU0_DIMM_SAA";
161"M_L_CPU0_SA_RSP<0>";
162"PWRGD_CHL_CPU0_DIMM";
163"I3C_SPD_DDRGL_CPU0_SCL";
164"P12V_MEM_CPU0\g";
165"GND\g";
166"GND\g";
167"GND\g";
168"P3V3_AUX\g";
169"I3C_SPD_DDRL_CPU0_SCL";
170"I3C_SPD_DDRL_CPU0_SDA";
171"I3C_SPD_DDRGL_CPU0_SDA";
172"PD_CHL_CPU0_DIMM_SAA";
%"TAP"
"1","(-6025,3925)","0","mstr_standard","I100";
;
CDS_LIB"mstr_standard"
BODY_TYPE"PLUMBING"
HDL_TAP"TRUE";
"B \NAC \NWC"8;
"S \NAC"
BN"8"104;
%"TAP"
"1","(-6025,3975)","0","mstr_standard","I101";
;
CDS_LIB"mstr_standard"
BODY_TYPE"PLUMBING"
HDL_TAP"TRUE";
"B \NAC \NWC"8;
"S \NAC"
BN"9"105;
%"TAP"
"1","(-6025,4025)","0","mstr_standard","I102";
;
CDS_LIB"mstr_standard"
BODY_TYPE"PLUMBING"
HDL_TAP"TRUE";
"B \NAC \NWC"8;
"S \NAC"
BN"10"106;
%"TAP"
"1","(-6025,4125)","0","mstr_standard","I103";
;
CDS_LIB"mstr_standard"
BODY_TYPE"PLUMBING"
HDL_TAP"TRUE";
"B \NAC \NWC"8;
"S \NAC"
BN"12"108;
%"TAP"
"1","(-6025,4075)","0","mstr_standard","I104";
;
CDS_LIB"mstr_standard"
BODY_TYPE"PLUMBING"
HDL_TAP"TRUE";
"B \NAC \NWC"8;
"S \NAC"
BN"11"107;
%"TAP"
"1","(-6025,4175)","0","mstr_standard","I105";
;
CDS_LIB"mstr_standard"
BODY_TYPE"PLUMBING"
HDL_TAP"TRUE";
"B \NAC \NWC"8;
"S \NAC"
BN"13"109;
%"TAP"
"1","(-6025,4225)","0","mstr_standard","I106";
;
CDS_LIB"mstr_standard"
BODY_TYPE"PLUMBING"
HDL_TAP"TRUE";
"B \NAC \NWC"8;
"S \NAC"
BN"14"110;
%"TAP"
"1","(-6025,4275)","0","mstr_standard","I107";
;
CDS_LIB"mstr_standard"
BODY_TYPE"PLUMBING"
HDL_TAP"TRUE";
"B \NAC \NWC"8;
"S \NAC"
BN"15"111;
%"TAP"
"1","(-6025,4325)","0","mstr_standard","I108";
;
CDS_LIB"mstr_standard"
BODY_TYPE"PLUMBING"
HDL_TAP"TRUE";
"B \NAC \NWC"8;
"S \NAC"
BN"16"112;
%"TAP"
"1","(-6025,4425)","0","mstr_standard","I109";
;
CDS_LIB"mstr_standard"
BODY_TYPE"PLUMBING"
HDL_TAP"TRUE";
"B \NAC \NWC"8;
"S \NAC"
BN"18"66;
%"TAP"
"1","(-6025,4375)","0","mstr_standard","I110";
;
CDS_LIB"mstr_standard"
BODY_TYPE"PLUMBING"
HDL_TAP"TRUE";
"B \NAC \NWC"8;
"S \NAC"
BN"17"113;
%"TAP"
"1","(-6025,4475)","0","mstr_standard","I111";
;
CDS_LIB"mstr_standard"
BODY_TYPE"PLUMBING"
HDL_TAP"TRUE";
"B \NAC \NWC"8;
"S \NAC"
BN"19"114;
%"TAP"
"1","(-6025,4525)","0","mstr_standard","I112";
;
CDS_LIB"mstr_standard"
BODY_TYPE"PLUMBING"
HDL_TAP"TRUE";
"B \NAC \NWC"8;
"S \NAC"
BN"20"115;
%"TAP"
"1","(-6025,4575)","0","mstr_standard","I113";
;
CDS_LIB"mstr_standard"
BODY_TYPE"PLUMBING"
HDL_TAP"TRUE";
"B \NAC \NWC"8;
"S \NAC"
BN"21"116;
%"TAP"
"1","(-6025,4625)","0","mstr_standard","I114";
;
CDS_LIB"mstr_standard"
BODY_TYPE"PLUMBING"
HDL_TAP"TRUE";
"B \NAC \NWC"8;
"S \NAC"
BN"22"117;
%"TAP"
"1","(-6025,4675)","0","mstr_standard","I115";
;
CDS_LIB"mstr_standard"
BODY_TYPE"PLUMBING"
HDL_TAP"TRUE";
"B \NAC \NWC"8;
"S \NAC"
BN"23"118;
%"TAP"
"1","(-6025,4725)","0","mstr_standard","I116";
;
CDS_LIB"mstr_standard"
BODY_TYPE"PLUMBING"
HDL_TAP"TRUE";
"B \NAC \NWC"8;
"S \NAC"
BN"24"119;
%"TAP"
"1","(-6025,4775)","0","mstr_standard","I117";
;
CDS_LIB"mstr_standard"
BODY_TYPE"PLUMBING"
HDL_TAP"TRUE";
"B \NAC \NWC"8;
"S \NAC"
BN"25"120;
%"TAP"
"1","(-6025,4825)","0","mstr_standard","I118";
;
CDS_LIB"mstr_standard"
BODY_TYPE"PLUMBING"
HDL_TAP"TRUE";
"B \NAC \NWC"8;
"S \NAC"
BN"26"121;
%"TAP"
"1","(-6025,4875)","0","mstr_standard","I119";
;
CDS_LIB"mstr_standard"
BODY_TYPE"PLUMBING"
HDL_TAP"TRUE";
"B \NAC \NWC"8;
"S \NAC"
BN"27"122;
%"TAP"
"1","(-6025,4925)","0","mstr_standard","I120";
;
CDS_LIB"mstr_standard"
BODY_TYPE"PLUMBING"
HDL_TAP"TRUE";
"B \NAC \NWC"8;
"S \NAC"
BN"28"123;
%"TAP"
"1","(-6025,5025)","0","mstr_standard","I121";
;
CDS_LIB"mstr_standard"
BODY_TYPE"PLUMBING"
HDL_TAP"TRUE";
"B \NAC \NWC"8;
"S \NAC"
BN"30"67;
%"TAP"
"1","(-6025,5075)","0","mstr_standard","I122";
;
CDS_LIB"mstr_standard"
BODY_TYPE"PLUMBING"
HDL_TAP"TRUE";
"B \NAC \NWC"8;
"S \NAC"
BN"31"68;
%"TAP"
"1","(-6025,4975)","0","mstr_standard","I123";
;
CDS_LIB"mstr_standard"
BODY_TYPE"PLUMBING"
HDL_TAP"TRUE";
"B \NAC \NWC"8;
"S \NAC"
BN"29"124;
%"GND"
"1","(-6450,700)","0","mstr_symbols","I126";
;
BOM_COST"MEM"
SIZE"1B"
CDS_LIB"mstr_symbols"
VOLTAGE"0.0"
BODY_TYPE"PLUMBING"
HDL_POWER"GND";
"A\NAC"1;
%"Q_RES"
"2","(-6450,925)","0","pure_quanta","I127";
;
LOCATION"R769"
$SEC"1"
CDS_SEC"1"
WATTAGE"1/16W"
MATERIAL"CHIP"
TOLERANCE"1%"
VALUE"84.5K"
PACK_TYPE"0402LF"
CDS_LIB"pure_quanta"
PART_NUMBER"CS38452FB05";
"A"
$PN"1"160;
"B"
$PN"2"1;
%"GND"
"1","(-2200,1750)","0","mstr_symbols","I138";
;
CDS_LIB"mstr_symbols"
SIZE"1B"
VOLTAGE"0.0"
BODY_TYPE"PLUMBING"
HDL_POWER"GND";
"A\NAC"167;
%"GND"
"1","(-400,1525)","0","mstr_symbols","I139";
;
CDS_LIB"mstr_symbols"
SIZE"1B"
VOLTAGE"0.0"
BODY_TYPE"PLUMBING"
HDL_POWER"GND";
"A\NAC"166;
%"SCONN288_DDR506112002KQ"
"3","(-1300,3525)","0","pure_quanta","I140";
;
LOCATION"J67"
$SEC"3"
CDS_SEC"3"
VALUE"SCONN288_DDR506112002KQ"
PART_TYPE"SMLF"
MATERIAL"IO"
CDS_LMAN_SYM_OUTLINE"-450,1800,450,-1750"
NEEDS_NO_SIZE"TRUE"
CDS_LIB"pure_quanta"
PART_NUMBER"DFHST8FS479";
"G3"
$PN"G3"166;
"G2"
$PN"G2"166;
"G1"
$PN"G1"166;
"VSS62"
$PN"141"166;
"VSS61"
$PN"139"166;
"VSS60"
$PN"136"166;
"VSS58"
$PN"132"166;
"VSS104"
$PN"240"167;
"VSS102"
$PN"235"167;
"VSS100"
$PN"230"167;
"VIN_BULK2"
$PN"146"164;
"VIN_BULK1"
$PN"145"164;
"VIN_BULK0"
$PN"1"164;
"VSS126"
$PN"288"167;
"VSS125"
$PN"286"167;
"VSS124"
$PN"284"167;
"VSS123"
$PN"281"167;
"VSS122"
$PN"279"167;
"VSS121"
$PN"277"167;
"VSS120"
$PN"275"167;
"VSS119"
$PN"273"167;
"VSS118"
$PN"270"167;
"VSS117"
$PN"268"167;
"VSS116"
$PN"266"167;
"VSS115"
$PN"264"167;
"VSS114"
$PN"262"167;
"VSS113"
$PN"259"167;
"VSS112"
$PN"257"167;
"VSS111"
$PN"255"167;
"VSS110"
$PN"253"167;
"VSS109"
$PN"251"167;
"VSS108"
$PN"248"167;
"VSS107"
$PN"246"167;
"VSS106"
$PN"244"167;
"VSS105"
$PN"242"167;
"VSS103"
$PN"237"167;
"VSS101"
$PN"233"167;
"VSS99"
$PN"228"167;
"VSS98"
$PN"226"167;
"VSS97"
$PN"224"167;
"VSS96"
$PN"222"167;
"VSS95"
$PN"219"167;
"VSS94"
$PN"216"167;
"VSS93"
$PN"214"167;
"VSS92"
$PN"212"167;
"VSS91"
$PN"210"167;
"VSS90"
$PN"208"167;
"VSS89"
$PN"206"167;
"VSS88"
$PN"204"167;
"VSS87"
$PN"202"167;
"VSS86"
$PN"199"167;
"VSS85"
$PN"197"167;
"VSS84"
$PN"195"167;
"VSS83"
$PN"193"167;
"VSS82"
$PN"191"167;
"VSS81"
$PN"188"167;
"VSS80"
$PN"186"167;
"VSS79"
$PN"184"167;
"VSS78"
$PN"182"167;
"VSS77"
$PN"180"167;
"VSS76"
$PN"177"167;
"VSS75"
$PN"175"167;
"VSS74"
$PN"173"167;
"VSS73"
$PN"171"167;
"VSS72"
$PN"169"167;
"VSS71"
$PN"166"167;
"VSS70"
$PN"164"167;
"VSS69"
$PN"162"167;
"VSS68"
$PN"160"167;
"VSS67"
$PN"158"167;
"VSS66"
$PN"155"167;
"VSS65"
$PN"153"167;
"VSS64"
$PN"151"167;
"VSS63"
$PN"143"166;
"VSS59"
$PN"134"166;
"VSS57"
$PN"130"166;
"VSS56"
$PN"128"166;
"VSS55"
$PN"125"166;
"VSS54"
$PN"123"166;
"VSS53"
$PN"121"166;
"VSS52"
$PN"119"166;
"VSS51"
$PN"117"166;
"VSS50"
$PN"114"166;
"VSS49"
$PN"112"166;
"VSS48"
$PN"110"166;
"VSS47"
$PN"108"166;
"VSS46"
$PN"106"166;
"VSS45"
$PN"103"166;
"VSS44"
$PN"101"166;
"VSS43"
$PN"99"166;
"VSS42"
$PN"97"166;
"VSS41"
$PN"95"166;
"VSS40"
$PN"92"166;
"VSS39"
$PN"90"166;
"VSS38"
$PN"88"166;
"VSS37"
$PN"85"166;
"VSS36"
$PN"83"166;
"VSS35"
$PN"81"166;
"VSS34"
$PN"79"166;
"VSS33"
$PN"77"166;
"VSS32"
$PN"75"166;
"VSS31"
$PN"73"166;
"VSS30"
$PN"71"166;
"VSS29"
$PN"69"166;
"VSS28"
$PN"67"166;
"VSS27"
$PN"65"166;
"VSS26"
$PN"63"166;
"VSS25"
$PN"61"166;
"VSS24"
$PN"59"166;
"VSS23"
$PN"57"166;
"VSS22"
$PN"54"166;
"VSS21"
$PN"52"166;
"VSS20"
$PN"50"166;
"VSS19"
$PN"48"166;
"VSS18"
$PN"46"166;
"VSS17"
$PN"43"166;
"VSS16"
$PN"41"166;
"VSS15"
$PN"39"166;
"VSS14"
$PN"37"166;
"VSS13"
$PN"35"166;
"VSS12"
$PN"32"166;
"VSS11"
$PN"30"166;
"VSS10"
$PN"28"166;
"VSS9"
$PN"26"166;
"VSS8"
$PN"24"166;
"VSS7"
$PN"21"166;
"VSS6"
$PN"19"166;
"VSS5"
$PN"17"166;
"VSS4"
$PN"15"166;
"VSS3"
$PN"13"166;
"VSS2"
$PN"10"166;
"VSS1"
$PN"8"166;
"VSS0"
$PN"6"166;
%"Q_CAP"
"1","(-8600,2900)","2","pure_quanta","I185";
;
LOCATION"C132"
$SEC"1"
CDS_SEC"1"
PACK_TYPE"0402"
VOLTAGE"25V"
TOLERANCE"10%"
VALUE"0.1UF"
MATERIAL"X7R"
BOM_COST"MEM"
CDS_LIB"pure_quanta"
ROOM""
PART_NUMBER"CH4104K1B00";
"B"
$PN"2"2;
"A"
$PN"1"168;
%"GND"
"1","(-8600,2675)","0","mstr_symbols","I186";
;
CDS_LIB"mstr_symbols"
SIZE"1B"
BOM_COST"MEM"
VOLTAGE"0"
ROOM"MEM_EFGH_DECOUPLING_CAPS"
BODY_TYPE"PLUMBING"
HDL_POWER"GND";
"A\NAC"2;
%"Q_RES"
"1","(-8475,1825)","2","pure_quanta","I188";
;
LOCATION"R302"
$SEC"1"
CDS_SEC"1"
VALUE"1K"
TOLERANCE"1%"
CDS_LIB"pure_quanta"
BOM_COST"MEM"
WATTAGE"1/16W"
MATERIAL"CHIP"
PACK_TYPE"0402LF"
ROOM""
PART_NUMBER"CS21002FB06";
"B"
$PN"2"16;
"A"
$PN"1"162;
%"Q_RES"
"2","(-8350,1975)","0","pure_quanta","I189";
;
LOCATION"R101"
$SEC"1"
CDS_SEC"1"
TOLERANCE"1%"
WATTAGE"1/16W"
MATERIAL"EMPTY"
PACK_TYPE"0402LF"
VALUE"1K"
CDS_LIB"pure_quanta"
BOM_COST"MEM"
ROOM""
PART_NUMBER"CS21002FB06";
"A"
$PN"1"3;
"B"
$PN"2"162;
%"VCC_CORE"
"1","(-8350,2150)","0","mstr_symbols","I190";
;
HDL_POWER"P3V3"
CDS_LIB"mstr_symbols"
VOLTAGE"3.3"
ROOM"PVCCINFAON_CPU0_CTRL";
"A"3;
%"TAP"
"1","(-3300,4250)","0","mstr_standard","I194";
;
CDS_LIB"mstr_standard"
BODY_TYPE"PLUMBING"
HDL_TAP"TRUE";
"B \NAC \NWC"10;
"S \NAC"
BN"9"29;
%"TAP"
"1","(-3500,4200)","0","mstr_standard","I195";
;
CDS_LIB"mstr_standard"
BODY_TYPE"PLUMBING"
HDL_TAP"TRUE";
"B \NAC \NWC"11;
"S \NAC"
BN"8"30;
%"TAP"
"1","(-3500,4300)","0","mstr_standard","I196";
;
CDS_LIB"mstr_standard"
BODY_TYPE"PLUMBING"
HDL_TAP"TRUE";
"B \NAC \NWC"11;
"S \NAC"
BN"9"28;
%"TAP"
"1","(-3300,4150)","0","mstr_standard","I197";
;
CDS_LIB"mstr_standard"
BODY_TYPE"PLUMBING"
HDL_TAP"TRUE";
"B \NAC \NWC"10;
"S \NAC"
BN"8"31;
%"TAP"
"1","(-3300,4050)","0","mstr_standard","I198";
;
CDS_LIB"mstr_standard"
BODY_TYPE"PLUMBING"
HDL_TAP"TRUE";
"B \NAC \NWC"10;
"S \NAC"
BN"7"65;
%"TAP"
"1","(-3300,3950)","0","mstr_standard","I199";
;
CDS_LIB"mstr_standard"
BODY_TYPE"PLUMBING"
HDL_TAP"TRUE";
"B \NAC \NWC"10;
"S \NAC"
BN"6"36;
%"TAP"
"1","(-3500,4100)","0","mstr_standard","I200";
;
CDS_LIB"mstr_standard"
BODY_TYPE"PLUMBING"
HDL_TAP"TRUE";
"B \NAC \NWC"11;
"S \NAC"
BN"7"33;
%"TAP"
"1","(-3500,4000)","0","mstr_standard","I201";
;
CDS_LIB"mstr_standard"
BODY_TYPE"PLUMBING"
HDL_TAP"TRUE";
"B \NAC \NWC"11;
"S \NAC"
BN"6"64;
%"TAP"
"1","(-3300,3750)","0","mstr_standard","I202";
;
CDS_LIB"mstr_standard"
BODY_TYPE"PLUMBING"
HDL_TAP"TRUE";
"B \NAC \NWC"10;
"S \NAC"
BN"4"44;
%"TAP"
"1","(-3300,3850)","0","mstr_standard","I203";
;
CDS_LIB"mstr_standard"
BODY_TYPE"PLUMBING"
HDL_TAP"TRUE";
"B \NAC \NWC"10;
"S \NAC"
BN"5"40;
%"TAP"
"1","(-3500,3900)","0","mstr_standard","I204";
;
CDS_LIB"mstr_standard"
BODY_TYPE"PLUMBING"
HDL_TAP"TRUE";
"B \NAC \NWC"11;
"S \NAC"
BN"5"39;
%"TAP"
"1","(-3500,3700)","0","mstr_standard","I205";
;
CDS_LIB"mstr_standard"
BODY_TYPE"PLUMBING"
HDL_TAP"TRUE";
"B \NAC \NWC"11;
"S \NAC"
BN"3"47;
%"TAP"
"1","(-3500,3800)","0","mstr_standard","I206";
;
CDS_LIB"mstr_standard"
BODY_TYPE"PLUMBING"
HDL_TAP"TRUE";
"B \NAC \NWC"11;
"S \NAC"
BN"4"43;
%"TAP"
"1","(-3300,3550)","0","mstr_standard","I207";
;
CDS_LIB"mstr_standard"
BODY_TYPE"PLUMBING"
HDL_TAP"TRUE";
"B \NAC \NWC"10;
"S \NAC"
BN"2"52;
%"TAP"
"1","(-3300,3650)","0","mstr_standard","I208";
;
CDS_LIB"mstr_standard"
BODY_TYPE"PLUMBING"
HDL_TAP"TRUE";
"B \NAC \NWC"10;
"S \NAC"
BN"3"48;
%"TAP"
"1","(-3300,3450)","0","mstr_standard","I209";
;
CDS_LIB"mstr_standard"
BODY_TYPE"PLUMBING"
HDL_TAP"TRUE";
"B \NAC \NWC"10;
"S \NAC"
BN"1"56;
%"TAP"
"1","(-3500,3600)","0","mstr_standard","I210";
;
CDS_LIB"mstr_standard"
BODY_TYPE"PLUMBING"
HDL_TAP"TRUE";
"B \NAC \NWC"11;
"S \NAC"
BN"2"51;
%"TAP"
"1","(-3500,3500)","0","mstr_standard","I211";
;
CDS_LIB"mstr_standard"
BODY_TYPE"PLUMBING"
HDL_TAP"TRUE";
"B \NAC \NWC"11;
"S \NAC"
BN"1"55;
%"TAP"
"1","(-3300,3200)","0","mstr_standard","I214";
;
CDS_LIB"mstr_standard"
BODY_TYPE"PLUMBING"
HDL_TAP"TRUE";
"B \NAC \NWC"13;
"S \NAC"
BN"9"27;
%"TAP"
"1","(-3300,3350)","0","mstr_standard","I215";
;
CDS_LIB"mstr_standard"
BODY_TYPE"PLUMBING"
HDL_TAP"TRUE";
"B \NAC \NWC"10;
"S \NAC"
BN"0"60;
%"TAP"
"1","(-3500,3400)","0","mstr_standard","I216";
;
CDS_LIB"mstr_standard"
BODY_TYPE"PLUMBING"
HDL_TAP"TRUE";
"B \NAC \NWC"11;
"S \NAC"
BN"0"59;
%"TAP"
"1","(-3500,3250)","0","mstr_standard","I217";
;
CDS_LIB"mstr_standard"
BODY_TYPE"PLUMBING"
HDL_TAP"TRUE";
"B \NAC \NWC"12;
"S \NAC"
BN"9"26;
%"TAP"
"1","(-3300,3100)","0","mstr_standard","I218";
;
CDS_LIB"mstr_standard"
BODY_TYPE"PLUMBING"
HDL_TAP"TRUE";
"B \NAC \NWC"13;
"S \NAC"
BN"8"62;
%"TAP"
"1","(-3300,3000)","0","mstr_standard","I219";
;
CDS_LIB"mstr_standard"
BODY_TYPE"PLUMBING"
HDL_TAP"TRUE";
"B \NAC \NWC"13;
"S \NAC"
BN"7"32;
%"SCONN288_DDR506112002KQ"
"1","(-6875,3325)","0","pure_quanta","I22";
;
LOCATION"J67"
$SEC"1"
CDS_SEC"1"
PART_TYPE"SMLF"
VALUE"SCONN288_DDR506112002KQ"
MATERIAL"IO"
CDS_LMAN_SYM_OUTLINE"-450,1900,450,-1850"
NEEDS_NO_SIZE"TRUE"
CDS_LIB"pure_quanta"
PART_NUMBER"DFHST8FS479";
"PWR_GOOD||FAIL_N"
$PN"147"162;
"DQ31_A"
$PN"194"68;
"CB7_A"
$PN"205"159;
"CB4_A"
$PN"58"158;
"CB1_A"
$PN"53"157;
"CB7_B"
$PN"236"156;
"ALERT_N \B"
$PN"62"14;
"CA0_A"
$PN"66"155;
"CA0_B"
$PN"76"154;
"CA1_A"
$PN"211"153;
"CA1_B"
$PN"221"152;
"CA2_A"
$PN"68"151;
"CA2_B"
$PN"78"150;
"CA3_A"
$PN"213"149;
"CA3_B"
$PN"223"148;
"CA4_A"
$PN"70"147;
"CA4_B"
$PN"80"146;
"CA5_A"
$PN"215"145;
"CA5_B"
$PN"225"144;
"CA6_A"
$PN"72"143;
"CA6_B"
$PN"82"142;
"CB6_A"
$PN"203"141;
"CB5_A"
$PN"60"140;
"CB3_A"
$PN"198"139;
"CB2_A"
$PN"196"138;
"CB0_A"
$PN"51"137;
"CB6_B"
$PN"234"136;
"CB5_B"
$PN"91"135;
"CB4_B"
$PN"89"21;
"CB3_B"
$PN"243"134;
"CB2_B"
$PN"241"133;
"CB1_B"
$PN"98"132;
"CB0_B"
$PN"96"131;
"CK_C \B"
$PN"218"130;
"CK_T"
$PN"217"129;
"CS0_A_N"
$PN"64"128;
"CS0_B_N"
$PN"84"127;
"CS1_A_N"
$PN"209"126;
"CS1_B_N"
$PN"229"125;
"DQ30_A"
$PN"192"67;
"DQ29_A"
$PN"49"124;
"DQ28_A"
$PN"47"123;
"DQ27_A"
$PN"187"122;
"DQ26_A"
$PN"185"121;
"DQ25_A"
$PN"42"120;
"DQ24_A"
$PN"40"119;
"DQ23_A"
$PN"183"118;
"DQ22_A"
$PN"181"117;
"DQ21_A"
$PN"38"116;
"DQ20_A"
$PN"36"115;
"DQ19_A"
$PN"176"114;
"DQ18_A"
$PN"174"66;
"DQ17_A"
$PN"31"113;
"DQ16_A"
$PN"29"112;
"DQ15_A"
$PN"172"111;
"DQ14_A"
$PN"170"110;
"DQ13_A"
$PN"27"109;
"DQ12_A"
$PN"25"108;
"DQ11_A"
$PN"165"107;
"DQ10_A"
$PN"163"106;
"DQ9_A"
$PN"20"105;
"DQ8_A"
$PN"18"104;
"DQ7_A"
$PN"161"103;
"DQ6_A"
$PN"159"102;
"DQ5_A"
$PN"16"101;
"DQ4_A"
$PN"14"24;
"DQ3_A"
$PN"154"23;
"DQ2_A"
$PN"152"22;
"DQ1_A"
$PN"9"100;
"DQ0_A"
$PN"7"99;
"DQ31_B"
$PN"287"98;
"DQ30_B"
$PN"285"97;
"DQ29_B"
$PN"142"96;
"DQ28_B"
$PN"140"95;
"DQ27_B"
$PN"280"94;
"DQ26_B"
$PN"278"93;
"DQ25_B"
$PN"135"92;
"DQ24_B"
$PN"133"91;
"DQ23_B"
$PN"276"90;
"DQ22_B"
$PN"274"89;
"DQ21_B"
$PN"131"88;
"DQ20_B"
$PN"129"87;
"DQ19_B"
$PN"269"86;
"DQ18_B"
$PN"267"85;
"DQ17_B"
$PN"124"17;
"DQ16_B"
$PN"122"84;
"DQ15_B"
$PN"265"83;
"DQ14_B"
$PN"263"82;
"DQ13_B"
$PN"120"81;
"DQ12_B"
$PN"118"80;
"DQ11_B"
$PN"258"20;
"DQ10_B"
$PN"256"79;
"DQ9_B"
$PN"113"19;
"DQ8_B"
$PN"111"78;
"DQ7_B"
$PN"254"18;
"DQ6_B"
$PN"252"77;
"DQ5_B"
$PN"109"76;
"DQ4_B"
$PN"107"75;
"DQ3_B"
$PN"247"74;
"DQ2_B"
$PN"245"73;
"DQ1_B"
$PN"102"72;
"DQ0_B"
$PN"100"71;
"HAS"
$PN"148"172;
"HSCL"
$PN"4"169;
"HSDA"
$PN"5"170;
"LBD||RSP_A_N"
$PN"86"161;
"LBS||RSP_B_N"
$PN"87"25;
"PAR_A"
$PN"74"70;
"PAR_B"
$PN"227"69;
"RESET_N \B"
$PN"207"15;
"RFU6"
$PN"232"0;
"RFU5"
$PN"231"0;
"RFU4"
$PN"220"0;
"RFU3"
$PN"150"0;
"RFU2"
$PN"149"0;
"RFU1"
$PN"144"0;
"RFU0"
$PN"2"0;
"VIN_MGMT"
$PN"3"168;
%"TAP"
"1","(-3500,3150)","0","mstr_standard","I220";
;
CDS_LIB"mstr_standard"
BODY_TYPE"PLUMBING"
HDL_TAP"TRUE";
"B \NAC \NWC"12;
"S \NAC"
BN"8"63;
%"TAP"
"1","(-3500,3050)","0","mstr_standard","I221";
;
CDS_LIB"mstr_standard"
BODY_TYPE"PLUMBING"
HDL_TAP"TRUE";
"B \NAC \NWC"12;
"S \NAC"
BN"7"61;
%"TAP"
"1","(-3500,2950)","0","mstr_standard","I222";
;
CDS_LIB"mstr_standard"
BODY_TYPE"PLUMBING"
HDL_TAP"TRUE";
"B \NAC \NWC"12;
"S \NAC"
BN"6"34;
%"TAP"
"1","(-3300,2800)","0","mstr_standard","I223";
;
CDS_LIB"mstr_standard"
BODY_TYPE"PLUMBING"
HDL_TAP"TRUE";
"B \NAC \NWC"13;
"S \NAC"
BN"5"38;
%"TAP"
"1","(-3300,2900)","0","mstr_standard","I224";
;
CDS_LIB"mstr_standard"
BODY_TYPE"PLUMBING"
HDL_TAP"TRUE";
"B \NAC \NWC"13;
"S \NAC"
BN"6"35;
%"TAP"
"1","(-3300,2700)","0","mstr_standard","I225";
;
CDS_LIB"mstr_standard"
BODY_TYPE"PLUMBING"
HDL_TAP"TRUE";
"B \NAC \NWC"13;
"S \NAC"
BN"4"42;
%"TAP"
"1","(-3500,2850)","0","mstr_standard","I226";
;
CDS_LIB"mstr_standard"
BODY_TYPE"PLUMBING"
HDL_TAP"TRUE";
"B \NAC \NWC"12;
"S \NAC"
BN"5"37;
%"TAP"
"1","(-3500,2750)","0","mstr_standard","I227";
;
CDS_LIB"mstr_standard"
BODY_TYPE"PLUMBING"
HDL_TAP"TRUE";
"B \NAC \NWC"12;
"S \NAC"
BN"4"41;
%"TAP"
"1","(-3300,2500)","0","mstr_standard","I228";
;
CDS_LIB"mstr_standard"
BODY_TYPE"PLUMBING"
HDL_TAP"TRUE";
"B \NAC \NWC"13;
"S \NAC"
BN"2"50;
%"TAP"
"1","(-3300,2600)","0","mstr_standard","I229";
;
CDS_LIB"mstr_standard"
BODY_TYPE"PLUMBING"
HDL_TAP"TRUE";
"B \NAC \NWC"13;
"S \NAC"
BN"3"46;
%"TAP"
"1","(-7725,2875)","2","mstr_standard","I23";
;
CDS_LIB"mstr_standard"
BODY_TYPE"PLUMBING"
HDL_TAP"TRUE";
"B \NAC \NWC"5;
"S \NAC"
BN"0"131;
%"TAP"
"1","(-3300,2400)","0","mstr_standard","I230";
;
CDS_LIB"mstr_standard"
BODY_TYPE"PLUMBING"
HDL_TAP"TRUE";
"B \NAC \NWC"13;
"S \NAC"
BN"1"54;
%"TAP"
"1","(-3500,2650)","0","mstr_standard","I231";
;
CDS_LIB"mstr_standard"
BODY_TYPE"PLUMBING"
HDL_TAP"TRUE";
"B \NAC \NWC"12;
"S \NAC"
BN"3"45;
%"TAP"
"1","(-3500,2550)","0","mstr_standard","I232";
;
CDS_LIB"mstr_standard"
BODY_TYPE"PLUMBING"
HDL_TAP"TRUE";
"B \NAC \NWC"12;
"S \NAC"
BN"2"49;
%"TAP"
"1","(-3500,2450)","0","mstr_standard","I233";
;
CDS_LIB"mstr_standard"
BODY_TYPE"PLUMBING"
HDL_TAP"TRUE";
"B \NAC \NWC"12;
"S \NAC"
BN"1"53;
%"TAP"
"1","(-3300,2300)","0","mstr_standard","I234";
;
CDS_LIB"mstr_standard"
BODY_TYPE"PLUMBING"
HDL_TAP"TRUE";
"B \NAC \NWC"13;
"S \NAC"
BN"0"58;
%"TAP"
"1","(-3500,2350)","0","mstr_standard","I235";
;
CDS_LIB"mstr_standard"
BODY_TYPE"PLUMBING"
HDL_TAP"TRUE";
"B \NAC \NWC"12;
"S \NAC"
BN"0"57;
%"SCONN288_DDR506112002KQ"
"2","(-4450,3300)","0","pure_quanta","I236";
;
LOCATION"J67"
$SEC"2"
CDS_SEC"2"
PART_TYPE"SMLF"
VALUE"SCONN288_DDR506112002KQ"
MATERIAL"IO"
CDS_LMAN_SYM_OUTLINE"-600,1150,600,-1150"
NEEDS_NO_SIZE"TRUE"
CDS_LIB"pure_quanta"
PART_NUMBER"DFHST8FS479";
"DQS7_A_C||TDQS7_A_C \B"
$PN"178"65;
"DQS6_A_T||TDQS6_A_T"
$PN"168"64;
"DQS8_B_T||TDQS8_B_T"
$PN"283"63;
"DQS8_B_C||TDQS8_B_C \B"
$PN"282"62;
"DQS7_B_T||TDQS7_B_T"
$PN"272"61;
"DQS0_A_C \B"
$PN"12"60;
"DQS0_A_T"
$PN"11"59;
"DQS0_B_C \B"
$PN"105"58;
"DQS0_B_T"
$PN"104"57;
"DQS1_A_C \B"
$PN"23"56;
"DQS1_A_T"
$PN"22"55;
"DQS1_B_C \B"
$PN"116"54;
"DQS1_B_T"
$PN"115"53;
"DQS2_A_C \B"
$PN"34"52;
"DQS2_A_T"
$PN"33"51;
"DQS2_B_C \B"
$PN"127"50;
"DQS2_B_T"
$PN"126"49;
"DQS3_A_C \B"
$PN"45"48;
"DQS3_A_T"
$PN"44"47;
"DQS3_B_C \B"
$PN"138"46;
"DQS3_B_T"
$PN"137"45;
"DQS4_A_C \B"
$PN"56"44;
"DQS4_A_T"
$PN"55"43;
"DQS4_B_C \B"
$PN"238"42;
"DQS4_B_T"
$PN"239"41;
"DQS5_A_C||TDQS5_A_C||DQS5_A_T||TDQS5_A_T \B"
$PN"156"40;
"DQS5_A_T||TDQS5_A_T"
$PN"157"39;
"DQS5_B_C||TDQS5_B_C \B"
$PN"249"38;
"DQS5_B_T||TDQS5_B_T"
$PN"250"37;
"DQS6_A_C||TDQS6_A_C||DQS6_A_T||TDQS6_A_T \B"
$PN"167"36;
"DQS6_B_C||TDQS6_B_C \B"
$PN"260"35;
"DQS6_B_T||TDQS6_B_T"
$PN"261"34;
"DQS7_A_T||TDQS7_A_T"
$PN"179"33;
"DQS7_B_C||TDQS7_B_C \B"
$PN"271"32;
"DQS8_A_C||TDQS8_A_C \B"
$PN"189"31;
"DQS8_A_T||TDQS8_A_T"
$PN"190"30;
"DQS9_A_C||TDQS9_A_C \B"
$PN"200"29;
"DQS9_A_T||TDQS9_A_T"
$PN"201"28;
"DQS9_B_C||TDQS9_B_C \B"
$PN"94"27;
"DQS9_B_T||TDQS9_B_T||DBI4_B_N"
$PN"93"26;
%"GND"
"1","(-2900,5250)","0","pure_quanta_power","I237";
;
SIZE"1B"
BOM_COST"MEM"
CDS_LIB"pure_quanta_power"
ROOM"MEM_EFGH_DECOUPLING_CAPS"
HDL_POWER"GND";
"A<SIZE-1..0>\NAC"165;
%"Q_CAP"
"1","(-2900,5600)","2","pure_quanta","I238";
;
LOCATION"C170"
$SEC"1"
CDS_SEC"1"
TOLERANCE"10%"
MATERIAL"X6S"
PACK_TYPE"C0805"
VOLTAGE"25V"
VALUE"10UF"
BOM_COST"MEM"
CDS_LIB"pure_quanta"
ROOM""
PART_NUMBER"CH6104KEA00";
"B"
$PN"2"165;
"A"
$PN"1"164;
%"Q_CAP"
"1","(-2325,5600)","2","pure_quanta","I239";
;
LOCATION"C171"
$SEC"1"
CDS_SEC"1"
MATERIAL"X6S"
PACK_TYPE"C0805"
VOLTAGE"25V"
VALUE"10UF"
TOLERANCE"10%"
BOM_COST"MEM"
CDS_LIB"pure_quanta"
ROOM""
PART_NUMBER"CH6104KEA00";
"B"
$PN"2"165;
"A"
$PN"1"164;
%"TAP"
"1","(-7725,2925)","2","mstr_standard","I24";
;
CDS_LIB"mstr_standard"
BODY_TYPE"PLUMBING"
HDL_TAP"TRUE";
"B \NAC \NWC"5;
"S \NAC"
BN"1"132;
%"UNIVERSAL_POWER"
"1","(-2900,5925)","0","pure_quanta_power","I240";
;
HDL_POWER"P12V_MEM_CPU0"
CDS_LIB"pure_quanta_power"
BOM_COST"VR_SYSTEM";
"A"164;
%"Q_RES"
"1","(-7775,2300)","0","pure_quanta","I242";
;
LOCATION"R1579"
$SEC"1"
CDS_SEC"1"
VALUE"49.9"
CDS_LIB"pure_quanta"
MATERIAL"CHIP"
PACK_TYPE"0402LF"
WATTAGE"1/16W"
TOLERANCE"1%"
PART_NUMBER"CS04992FB07";
"B"
$PN"2"169;
"A"
$PN"1"163;
%"Q_RES"
"1","(-8125,2525)","0","pure_quanta","I243";
;
LOCATION"R1686"
$SEC"1"
CDS_SEC"1"
PACK_TYPE"0402LF"
VALUE"10"
MATERIAL"CHIP"
CDS_LIB"pure_quanta"
TOLERANCE"1%"
WATTAGE"1/16W"
PART_NUMBER"CS01002FB07";
"B"
$PN"2"170;
"A"
$PN"1"171;
%"TAP"
"1","(-7725,2975)","2","mstr_standard","I25";
;
CDS_LIB"mstr_standard"
BODY_TYPE"PLUMBING"
HDL_TAP"TRUE";
"B \NAC \NWC"5;
"S \NAC"
BN"2"133;
%"TAP"
"1","(-7725,3075)","2","mstr_standard","I26";
;
CDS_LIB"mstr_standard"
BODY_TYPE"PLUMBING"
HDL_TAP"TRUE";
"B \NAC \NWC"5;
"S \NAC"
BN"4"21;
%"TAP"
"1","(-7725,3125)","2","mstr_standard","I27";
;
CDS_LIB"mstr_standard"
BODY_TYPE"PLUMBING"
HDL_TAP"TRUE";
"B \NAC \NWC"5;
"S \NAC"
BN"5"135;
%"TAP"
"1","(-7725,3025)","2","mstr_standard","I28";
;
CDS_LIB"mstr_standard"
BODY_TYPE"PLUMBING"
HDL_TAP"TRUE";
"B \NAC \NWC"5;
"S \NAC"
BN"3"134;
%"TAP"
"1","(-7725,3225)","2","mstr_standard","I29";
;
CDS_LIB"mstr_standard"
BODY_TYPE"PLUMBING"
HDL_TAP"TRUE";
"B \NAC \NWC"5;
"S \NAC"
BN"7"156;
%"TAP"
"1","(-7725,3375)","2","mstr_standard","I30";
;
CDS_LIB"mstr_standard"
BODY_TYPE"PLUMBING"
HDL_TAP"TRUE";
"B \NAC \NWC"4;
"S \NAC"
BN"1"157;
%"TAP"
"1","(-7725,3325)","2","mstr_standard","I31";
;
CDS_LIB"mstr_standard"
BODY_TYPE"PLUMBING"
HDL_TAP"TRUE";
"B \NAC \NWC"4;
"S \NAC"
BN"0"137;
%"TAP"
"1","(-7725,3175)","2","mstr_standard","I32";
;
CDS_LIB"mstr_standard"
BODY_TYPE"PLUMBING"
HDL_TAP"TRUE";
"B \NAC \NWC"5;
"S \NAC"
BN"6"136;
%"TAP"
"1","(-6025,1875)","0","mstr_standard","I33";
;
CDS_LIB"mstr_standard"
BODY_TYPE"PLUMBING"
HDL_TAP"TRUE";
"B \NAC \NWC"9;
"S \NAC"
BN"0"71;
%"TAP"
"1","(-6025,1925)","0","mstr_standard","I34";
;
CDS_LIB"mstr_standard"
BODY_TYPE"PLUMBING"
HDL_TAP"TRUE";
"B \NAC \NWC"9;
"S \NAC"
BN"1"72;
%"TAP"
"1","(-6025,1975)","0","mstr_standard","I35";
;
CDS_LIB"mstr_standard"
BODY_TYPE"PLUMBING"
HDL_TAP"TRUE";
"B \NAC \NWC"9;
"S \NAC"
BN"2"73;
%"TAP"
"1","(-6025,2025)","0","mstr_standard","I36";
;
CDS_LIB"mstr_standard"
BODY_TYPE"PLUMBING"
HDL_TAP"TRUE";
"B \NAC \NWC"9;
"S \NAC"
BN"3"74;
%"TAP"
"1","(-6025,2075)","0","mstr_standard","I37";
;
CDS_LIB"mstr_standard"
BODY_TYPE"PLUMBING"
HDL_TAP"TRUE";
"B \NAC \NWC"9;
"S \NAC"
BN"4"75;
%"TAP"
"1","(-6025,2125)","0","mstr_standard","I38";
;
CDS_LIB"mstr_standard"
BODY_TYPE"PLUMBING"
HDL_TAP"TRUE";
"B \NAC \NWC"9;
"S \NAC"
BN"5"76;
%"TAP"
"1","(-6025,2175)","0","mstr_standard","I39";
;
CDS_LIB"mstr_standard"
BODY_TYPE"PLUMBING"
HDL_TAP"TRUE";
"B \NAC \NWC"9;
"S \NAC"
BN"6"77;
%"TAP"
"1","(-6025,2225)","0","mstr_standard","I40";
;
CDS_LIB"mstr_standard"
BODY_TYPE"PLUMBING"
HDL_TAP"TRUE";
"B \NAC \NWC"9;
"S \NAC"
BN"7"18;
%"TAP"
"1","(-6025,2275)","0","mstr_standard","I41";
;
CDS_LIB"mstr_standard"
BODY_TYPE"PLUMBING"
HDL_TAP"TRUE";
"B \NAC \NWC"9;
"S \NAC"
BN"8"78;
%"TAP"
"1","(-6025,2375)","0","mstr_standard","I42";
;
CDS_LIB"mstr_standard"
BODY_TYPE"PLUMBING"
HDL_TAP"TRUE";
"B \NAC \NWC"9;
"S \NAC"
BN"10"79;
%"TAP"
"1","(-6025,2325)","0","mstr_standard","I43";
;
CDS_LIB"mstr_standard"
BODY_TYPE"PLUMBING"
HDL_TAP"TRUE";
"B \NAC \NWC"9;
"S \NAC"
BN"9"19;
%"TAP"
"1","(-6025,2425)","0","mstr_standard","I44";
;
CDS_LIB"mstr_standard"
BODY_TYPE"PLUMBING"
HDL_TAP"TRUE";
"B \NAC \NWC"9;
"S \NAC"
BN"11"20;
%"TAP"
"1","(-6025,2475)","0","mstr_standard","I45";
;
CDS_LIB"mstr_standard"
BODY_TYPE"PLUMBING"
HDL_TAP"TRUE";
"B \NAC \NWC"9;
"S \NAC"
BN"12"80;
%"TAP"
"1","(-6025,2525)","0","mstr_standard","I46";
;
CDS_LIB"mstr_standard"
BODY_TYPE"PLUMBING"
HDL_TAP"TRUE";
"B \NAC \NWC"9;
"S \NAC"
BN"13"81;
%"TAP"
"1","(-6025,2575)","0","mstr_standard","I47";
;
CDS_LIB"mstr_standard"
BODY_TYPE"PLUMBING"
HDL_TAP"TRUE";
"B \NAC \NWC"9;
"S \NAC"
BN"14"82;
%"TAP"
"1","(-6025,2625)","0","mstr_standard","I48";
;
CDS_LIB"mstr_standard"
BODY_TYPE"PLUMBING"
HDL_TAP"TRUE";
"B \NAC \NWC"9;
"S \NAC"
BN"15"83;
%"TAP"
"1","(-6025,2675)","0","mstr_standard","I49";
;
CDS_LIB"mstr_standard"
BODY_TYPE"PLUMBING"
HDL_TAP"TRUE";
"B \NAC \NWC"9;
"S \NAC"
BN"16"84;
%"TAP"
"1","(-6025,2725)","0","mstr_standard","I50";
;
CDS_LIB"mstr_standard"
BODY_TYPE"PLUMBING"
HDL_TAP"TRUE";
"B \NAC \NWC"9;
"S \NAC"
BN"17"17;
%"TAP"
"1","(-6025,2775)","0","mstr_standard","I51";
;
CDS_LIB"mstr_standard"
BODY_TYPE"PLUMBING"
HDL_TAP"TRUE";
"B \NAC \NWC"9;
"S \NAC"
BN"18"85;
%"TAP"
"1","(-6025,2825)","0","mstr_standard","I52";
;
CDS_LIB"mstr_standard"
BODY_TYPE"PLUMBING"
HDL_TAP"TRUE";
"B \NAC \NWC"9;
"S \NAC"
BN"19"86;
%"TAP"
"1","(-6025,2875)","0","mstr_standard","I53";
;
CDS_LIB"mstr_standard"
BODY_TYPE"PLUMBING"
HDL_TAP"TRUE";
"B \NAC \NWC"9;
"S \NAC"
BN"20"87;
%"TAP"
"1","(-6025,2925)","0","mstr_standard","I54";
;
CDS_LIB"mstr_standard"
BODY_TYPE"PLUMBING"
HDL_TAP"TRUE";
"B \NAC \NWC"9;
"S \NAC"
BN"21"88;
%"TAP"
"1","(-6025,2975)","0","mstr_standard","I55";
;
CDS_LIB"mstr_standard"
BODY_TYPE"PLUMBING"
HDL_TAP"TRUE";
"B \NAC \NWC"9;
"S \NAC"
BN"22"89;
%"TAP"
"1","(-6025,3025)","0","mstr_standard","I56";
;
CDS_LIB"mstr_standard"
BODY_TYPE"PLUMBING"
HDL_TAP"TRUE";
"B \NAC \NWC"9;
"S \NAC"
BN"23"90;
%"TAP"
"1","(-6025,3075)","0","mstr_standard","I57";
;
CDS_LIB"mstr_standard"
BODY_TYPE"PLUMBING"
HDL_TAP"TRUE";
"B \NAC \NWC"9;
"S \NAC"
BN"24"91;
%"TAP"
"1","(-6025,3125)","0","mstr_standard","I58";
;
CDS_LIB"mstr_standard"
BODY_TYPE"PLUMBING"
HDL_TAP"TRUE";
"B \NAC \NWC"9;
"S \NAC"
BN"25"92;
%"TAP"
"1","(-6025,3175)","0","mstr_standard","I59";
;
CDS_LIB"mstr_standard"
BODY_TYPE"PLUMBING"
HDL_TAP"TRUE";
"B \NAC \NWC"9;
"S \NAC"
BN"26"93;
%"TAP"
"1","(-6025,3225)","0","mstr_standard","I60";
;
CDS_LIB"mstr_standard"
BODY_TYPE"PLUMBING"
HDL_TAP"TRUE";
"B \NAC \NWC"9;
"S \NAC"
BN"27"94;
%"TAP"
"1","(-6025,3275)","0","mstr_standard","I61";
;
CDS_LIB"mstr_standard"
BODY_TYPE"PLUMBING"
HDL_TAP"TRUE";
"B \NAC \NWC"9;
"S \NAC"
BN"28"95;
%"TAP"
"1","(-6025,3325)","0","mstr_standard","I62";
;
CDS_LIB"mstr_standard"
BODY_TYPE"PLUMBING"
HDL_TAP"TRUE";
"B \NAC \NWC"9;
"S \NAC"
BN"29"96;
%"TAP"
"1","(-6025,3375)","0","mstr_standard","I63";
;
CDS_LIB"mstr_standard"
BODY_TYPE"PLUMBING"
HDL_TAP"TRUE";
"B \NAC \NWC"9;
"S \NAC"
BN"30"97;
%"TAP"
"1","(-7725,3425)","2","mstr_standard","I71";
;
CDS_LIB"mstr_standard"
BODY_TYPE"PLUMBING"
HDL_TAP"TRUE";
"B \NAC \NWC"4;
"S \NAC"
BN"2"138;
%"TAP"
"1","(-7725,3475)","2","mstr_standard","I72";
;
CDS_LIB"mstr_standard"
BODY_TYPE"PLUMBING"
HDL_TAP"TRUE";
"B \NAC \NWC"4;
"S \NAC"
BN"3"139;
%"TAP"
"1","(-7725,3575)","2","mstr_standard","I73";
;
CDS_LIB"mstr_standard"
BODY_TYPE"PLUMBING"
HDL_TAP"TRUE";
"B \NAC \NWC"4;
"S \NAC"
BN"5"140;
%"TAP"
"1","(-7725,3625)","2","mstr_standard","I74";
;
CDS_LIB"mstr_standard"
BODY_TYPE"PLUMBING"
HDL_TAP"TRUE";
"B \NAC \NWC"4;
"S \NAC"
BN"6"141;
%"TAP"
"1","(-7725,3525)","2","mstr_standard","I75";
;
CDS_LIB"mstr_standard"
BODY_TYPE"PLUMBING"
HDL_TAP"TRUE";
"B \NAC \NWC"4;
"S \NAC"
BN"4"158;
%"TAP"
"1","(-7725,3675)","2","mstr_standard","I76";
;
CDS_LIB"mstr_standard"
BODY_TYPE"PLUMBING"
HDL_TAP"TRUE";
"B \NAC \NWC"4;
"S \NAC"
BN"7"159;
%"TAP"
"1","(-7725,4375)","2","mstr_standard","I77";
;
CDS_LIB"mstr_standard"
BODY_TYPE"PLUMBING"
HDL_TAP"TRUE";
"B \NAC \NWC"7;
"S \NAC"
BN"0"154;
%"TAP"
"1","(-7725,4425)","2","mstr_standard","I78";
;
CDS_LIB"mstr_standard"
BODY_TYPE"PLUMBING"
HDL_TAP"TRUE";
"B \NAC \NWC"7;
"S \NAC"
BN"1"152;
%"TAP"
"1","(-7725,4475)","2","mstr_standard","I79";
;
CDS_LIB"mstr_standard"
BODY_TYPE"PLUMBING"
HDL_TAP"TRUE";
"B \NAC \NWC"7;
"S \NAC"
BN"2"150;
%"TAP"
"1","(-7725,4525)","2","mstr_standard","I80";
;
CDS_LIB"mstr_standard"
BODY_TYPE"PLUMBING"
HDL_TAP"TRUE";
"B \NAC \NWC"7;
"S \NAC"
BN"3"148;
%"TAP"
"1","(-7725,4575)","2","mstr_standard","I81";
;
CDS_LIB"mstr_standard"
BODY_TYPE"PLUMBING"
HDL_TAP"TRUE";
"B \NAC \NWC"7;
"S \NAC"
BN"4"146;
%"TAP"
"1","(-7725,4675)","2","mstr_standard","I82";
;
CDS_LIB"mstr_standard"
BODY_TYPE"PLUMBING"
HDL_TAP"TRUE";
"B \NAC \NWC"7;
"S \NAC"
BN"6"142;
%"TAP"
"1","(-7725,4625)","2","mstr_standard","I83";
;
CDS_LIB"mstr_standard"
BODY_TYPE"PLUMBING"
HDL_TAP"TRUE";
"B \NAC \NWC"7;
"S \NAC"
BN"5"144;
%"TAP"
"1","(-7725,4825)","2","mstr_standard","I84";
;
CDS_LIB"mstr_standard"
BODY_TYPE"PLUMBING"
HDL_TAP"TRUE";
"B \NAC \NWC"6;
"S \NAC"
BN"1"153;
%"TAP"
"1","(-7725,4875)","2","mstr_standard","I85";
;
CDS_LIB"mstr_standard"
BODY_TYPE"PLUMBING"
HDL_TAP"TRUE";
"B \NAC \NWC"6;
"S \NAC"
BN"2"151;
%"TAP"
"1","(-7725,4925)","2","mstr_standard","I86";
;
CDS_LIB"mstr_standard"
BODY_TYPE"PLUMBING"
HDL_TAP"TRUE";
"B \NAC \NWC"6;
"S \NAC"
BN"3"149;
%"TAP"
"1","(-7725,4775)","2","mstr_standard","I87";
;
CDS_LIB"mstr_standard"
BODY_TYPE"PLUMBING"
HDL_TAP"TRUE";
"B \NAC \NWC"6;
"S \NAC"
BN"0"155;
%"TAP"
"1","(-7725,5025)","2","mstr_standard","I88";
;
CDS_LIB"mstr_standard"
BODY_TYPE"PLUMBING"
HDL_TAP"TRUE";
"B \NAC \NWC"6;
"S \NAC"
BN"5"145;
%"TAP"
"1","(-7725,5075)","2","mstr_standard","I89";
;
CDS_LIB"mstr_standard"
BODY_TYPE"PLUMBING"
HDL_TAP"TRUE";
"B \NAC \NWC"6;
"S \NAC"
BN"6"143;
%"VCC_CORE"
"1","(-8500,3100)","0","mstr_symbols","I9";
;
HDL_POWER"P3V3_AUX"
CDS_LIB"mstr_symbols"
VOLTAGE"3.3"
ROOM"PVCCINFAON_CPU0_CTRL";
"A"168;
%"TAP"
"1","(-7725,4975)","2","mstr_standard","I90";
;
CDS_LIB"mstr_standard"
BODY_TYPE"PLUMBING"
HDL_TAP"TRUE";
"B \NAC \NWC"6;
"S \NAC"
BN"4"147;
%"TAP"
"1","(-6025,3425)","0","mstr_standard","I91";
;
CDS_LIB"mstr_standard"
BODY_TYPE"PLUMBING"
HDL_TAP"TRUE";
"B \NAC \NWC"9;
"S \NAC"
BN"31"98;
%"TAP"
"1","(-6025,3525)","0","mstr_standard","I92";
;
CDS_LIB"mstr_standard"
BODY_TYPE"PLUMBING"
HDL_TAP"TRUE";
"B \NAC \NWC"8;
"S \NAC"
BN"0"99;
%"TAP"
"1","(-6025,3575)","0","mstr_standard","I93";
;
CDS_LIB"mstr_standard"
BODY_TYPE"PLUMBING"
HDL_TAP"TRUE";
"B \NAC \NWC"8;
"S \NAC"
BN"1"100;
%"TAP"
"1","(-6025,3625)","0","mstr_standard","I94";
;
CDS_LIB"mstr_standard"
BODY_TYPE"PLUMBING"
HDL_TAP"TRUE";
"B \NAC \NWC"8;
"S \NAC"
BN"2"22;
%"TAP"
"1","(-6025,3675)","0","mstr_standard","I95";
;
CDS_LIB"mstr_standard"
BODY_TYPE"PLUMBING"
HDL_TAP"TRUE";
"B \NAC \NWC"8;
"S \NAC"
BN"3"23;
%"TAP"
"1","(-6025,3725)","0","mstr_standard","I96";
;
CDS_LIB"mstr_standard"
BODY_TYPE"PLUMBING"
HDL_TAP"TRUE";
"B \NAC \NWC"8;
"S \NAC"
BN"4"24;
%"TAP"
"1","(-6025,3775)","0","mstr_standard","I97";
;
CDS_LIB"mstr_standard"
BODY_TYPE"PLUMBING"
HDL_TAP"TRUE";
"B \NAC \NWC"8;
"S \NAC"
BN"5"101;
%"TAP"
"1","(-6025,3825)","0","mstr_standard","I98";
;
CDS_LIB"mstr_standard"
BODY_TYPE"PLUMBING"
HDL_TAP"TRUE";
"B \NAC \NWC"8;
"S \NAC"
BN"6"102;
%"TAP"
"1","(-6025,3875)","0","mstr_standard","I99";
;
CDS_LIB"mstr_standard"
BODY_TYPE"PLUMBING"
HDL_TAP"TRUE";
"B \NAC \NWC"8;
"S \NAC"
BN"7"103;
END.
